# SCM (Grand Teton) — schematic netlist excerpt (pin names and nets, part order shuffled) for the footprints in the layout excerpt that follows; sources: Cadence DE-HDL packaged netlist, KiCad conversion of 12092022_DA0F0TMDCD0_F0T_Management_Board_D_brd_V3_OCP.brd

U1  K4A8G165WCBCTD  K4A8G165WC-BCTD IC  pkg BGA96XB  page 20
  VDDQ0  = P1V2_AUX
  VSSQ0  = GND
  DQU0  = M_BMC_DDR4_DQ<8>
  DQSU_C  = M_BMC_DDR4_DQS1_N
  VSSQ1  = GND
  VDDQ1  = P1V2_AUX
  VPP0  = P2V5_AUX
  VSS0  = GND
  VDD0  = P1V2_AUX
  DQSU_T  = M_BMC_DDR4_DQS1_P
  DQU1  = M_BMC_DDR4_DQ<9>
  VDD1  = P1V2_AUX
  VDDQ2  = P1V2_AUX
  DQU4  = M_BMC_DDR4_DQ<12>
  DQU2  = M_BMC_DDR4_DQ<10>
  DQU3  = M_BMC_DDR4_DQ<11>
  DQU5  = M_BMC_DDR4_DQ<13>
  VSSQ2  = GND
  VDD2  = P1V2_AUX
  VSSQ3  = GND
  DQU6  = M_BMC_DDR4_DQ<14>
  DQU7  = M_BMC_DDR4_DQ<15>
  VSSQ4  = GND
  VDDQ3  = P1V2_AUX
  VSS1  = GND
  \dmu_n||dbiu_n\  = M_BMC_DDR4_MDM1
  VSSQ5  = GND
  \dml_n||dbil_n\  = M_BMC_DDR4_MDM0
  VSSQ6  = GND
  VSS2  = M_BMC_DDR4_ZQU
  VSSQ7  = GND
  VDDQ4  = P1V2_AUX
  DQSL_C  = M_BMC_DDR4_DQS0_N
  DQL1  = M_BMC_DDR4_DQ<1>
  VDDQ5  = P1V2_AUX
  ZQ  = PD_M_BMC_DDR4_ZQ
  VDDQ6  = P1V2_AUX
  DQL0  = M_BMC_DDR4_DQ<0>
  DQSL_T  = M_BMC_DDR4_DQS0_P
  VDD3  = P1V2_AUX
  VSS3  = GND
  VDDQ7  = P1V2_AUX
  VSSQ8  = GND
  DQL4  = M_BMC_DDR4_DQ<4>
  DQL2  = M_BMC_DDR4_DQ<2>
  DQL3  = M_BMC_DDR4_DQ<3>
  DQL5  = M_BMC_DDR4_DQ<5>
  VSSQ9  = GND
  VDD4  = P1V2_AUX
  VDDQ8  = P1V2_AUX
  DQL6  = M_BMC_DDR4_DQ<6>
  DQL7  = M_BMC_DDR4_DQ<7>
  VDDQ9  = P1V2_AUX
  VDD5  = P1V2_AUX
  VSS4  = GND
  CKE  = M_BMC_DDR4_MCKE
  ODT  = M_BMC_DDR4_MODT
  CK_T  = M_BMC_DDR4_MCLK_DP
  CK_C  = M_BMC_DDR4_MCLK_DN
  VSS5  = GND
  VDD6  = P1V2_AUX
  \we_n||a14\  = M_BMC_DDR4_MWE_N
  ACT_N  = M_BMC_DDR4_MACT_N
  CS_N  = M_BMC_DDR4_MCS_N
  RAS_N  = M_BMC_DDR4_MRAS_N
  VDD7  = P1V2_AUX
  VREFCA  = P0V6_DDR_VREF_AUX
  BG0  = M_BMC_DDR4_MBG0
  \a10||ap\  = M_BMC_DDR4_MA<10>
  \a12||bc_n\  = M_BMC_DDR4_MA<12>
  \cas_n||a15\  = M_BMC_DDR4_MCAS_N
  VSS6  = M_BMC_DDR4_BG1
  VSS7  = GND
  BA0  = M_BMC_DDR4_MBA0
  A4  = M_BMC_DDR4_MA<4>
  A3  = M_BMC_DDR4_MA<3>
  BA1  = M_BMC_DDR4_MBA1
  TEN  = PD_M_BMC_DDR4_TEN
  RESET_N  = M_BMC_DDR4_RST_N
  A6  = M_BMC_DDR4_MA<6>
  A0  = M_BMC_DDR4_MA<0>
  A1  = M_BMC_DDR4_MA<1>
  A5  = M_BMC_DDR4_MA<5>
  ALERT_N  = M_BMC_DDR4_ALERT_N
  VDD8  = P1V2_AUX
  A8  = M_BMC_DDR4_MA<8>
  A2  = M_BMC_DDR4_MA<2>
  A9  = M_BMC_DDR4_MA<9>
  A7  = M_BMC_DDR4_MA<7>
  VPP1  = P2V5_AUX
  VSS8  = GND
  A11  = M_BMC_DDR4_MA<11>
  PAR  = PD_M_BMC_DDR4_PAR
  NC1  = GND
  A13  = M_BMC_DDR4_MA<13>
  VDD9  = P1V2_AUX

(kicad_pcb
	(version 20260206)
	(generator "pcbnew")
	(generator_version "10.0")
	(general
		(thickness 1.6)
		(legacy_teardrops no)
	)
	(paper "A4")
	(title_block
		(title "12092022_DA0F0TMDCD0_F0T_Management_Board_D_brd_V3_OCP.brd")
		(comment 1 "Grand Teton / footprint 201 of 1440 (U1), pads 1-48 of 96")
	)
	(layers
		(0 "F.Cu" signal "TOP")
		(4 "In1.Cu" signal "GND")
		(6 "In2.Cu" signal "IN1")
		(8 "In3.Cu" signal "GND1")
		(10 "In4.Cu" signal "IN2")
		(12 "In5.Cu" signal "VCC")
		(14 "In6.Cu" signal "VCC1")
		(16 "In7.Cu" signal "IN3")
		(18 "In8.Cu" signal "GND2")
		(20 "In9.Cu" signal "IN4")
		(22 "In10.Cu" signal "GND3")
		(2 "B.Cu" signal "BOTTOM")
		(9 "F.Adhes" user "F.Adhesive")
		(11 "B.Adhes" user "B.Adhesive")
		(13 "F.Paste" user "Package Geometry/Pastemask Top")
		(15 "B.Paste" user "Package Geometry/Pastemask Bottom")
		(5 "F.SilkS" user "Ref Des/Silkscreen Top")
		(7 "B.SilkS" user "Ref Des/Silkscreen Bottom")
		(1 "F.Mask" user "Board Geometry/Soldermask Top")
		(3 "B.Mask" user "Board Geometry/Soldermask Bottom")
		(17 "Dwgs.User" user "User.Drawings")
		(19 "Cmts.User" user "User.Comments")
		(21 "Eco1.User" user "User.Eco1")
		(23 "Eco2.User" user "User.Eco2")
		(25 "Edge.Cuts" user "Board Geometry/Outline")
		(27 "Margin" user)
		(31 "F.CrtYd" user "Package Geometry/Place Bound Top")
		(29 "B.CrtYd" user "Package Geometry/Place Bound Bottom")
		(35 "F.Fab" user "Ref Des/Assembly Top")
		(33 "B.Fab" user "Ref Des/Assembly Bottom")
	)
	(footprint ""
		(layer "F.Cu")
		(at 76.252324 -47.907448)
		(property "Reference" "U1"
			(at -4.664456 -10.397744 0)
			(unlocked yes)
			(layer "F.SilkS")
			(effects
				(font
					(size 0.7874 0.5842)
					(thickness 0.1524)
				)
				(justify left)
			)
		)
		(property "Value" ""
			(at 0 0 0)
			(layer "F.Fab")
			(effects
				(font
					(size 1.27 1.27)
				)
			)
		)
		(duplicate_pad_numbers_are_jumpers no)
		(pad "A1" smd circle
			(at -3.199892 -5.999988)
			(size 0.3683 0.3683)
			(layers "F.Cu" "F.Mask" "F.Paste")
			(net "P1V2_AUX")
		)
		(pad "A2" smd circle
			(at -2.400046 -5.999988)
			(size 0.3683 0.3683)
			(layers "F.Cu" "F.Mask" "F.Paste")
			(net "GND")
		)
		(pad "A3" smd circle
			(at -1.599946 -5.999988)
			(size 0.3683 0.3683)
			(layers "F.Cu" "F.Mask" "F.Paste")
			(net "M_BMC_DDR4_DQ<8>")
		)
		(pad "A7" smd circle
			(at 1.599946 -5.999988)
			(size 0.3683 0.3683)
			(layers "F.Cu" "F.Mask" "F.Paste")
			(net "M_BMC_DDR4_DQS1_N")
		)
		(pad "A8" smd circle
			(at 2.400046 -5.999988)
			(size 0.3683 0.3683)
			(layers "F.Cu" "F.Mask" "F.Paste")
			(net "GND")
		)
		(pad "A9" smd circle
			(at 3.199892 -5.999988)
			(size 0.3683 0.3683)
			(layers "F.Cu" "F.Mask" "F.Paste")
			(net "P1V2_AUX")
		)
		(pad "B1" smd circle
			(at -3.199892 -5.199888)
			(size 0.3683 0.3683)
			(layers "F.Cu" "F.Mask" "F.Paste")
			(net "P2V5_AUX")
		)
		(pad "B2" smd circle
			(at -2.400046 -5.199888)
			(size 0.3683 0.3683)
			(layers "F.Cu" "F.Mask" "F.Paste")
			(net "GND")
		)
		(pad "B3" smd circle
			(at -1.599946 -5.199888)
			(size 0.3683 0.3683)
			(layers "F.Cu" "F.Mask" "F.Paste")
			(net "P1V2_AUX")
		)
		(pad "B7" smd circle
			(at 1.599946 -5.199888)
			(size 0.3683 0.3683)
			(layers "F.Cu" "F.Mask" "F.Paste")
			(net "M_BMC_DDR4_DQS1_P")
		)
		(pad "B8" smd circle
			(at 2.400046 -5.199888)
			(size 0.3683 0.3683)
			(layers "F.Cu" "F.Mask" "F.Paste")
			(net "M_BMC_DDR4_DQ<9>")
		)
		(pad "B9" smd circle
			(at 3.199892 -5.199888)
			(size 0.3683 0.3683)
			(layers "F.Cu" "F.Mask" "F.Paste")
			(net "P1V2_AUX")
		)
		(pad "C1" smd circle
			(at -3.199892 -4.400042)
			(size 0.3683 0.3683)
			(layers "F.Cu" "F.Mask" "F.Paste")
			(net "P1V2_AUX")
		)
		(pad "C2" smd circle
			(at -2.400046 -4.400042)
			(size 0.3683 0.3683)
			(layers "F.Cu" "F.Mask" "F.Paste")
			(net "M_BMC_DDR4_DQ<12>")
		)
		(pad "C3" smd circle
			(at -1.599946 -4.400042)
			(size 0.3683 0.3683)
			(layers "F.Cu" "F.Mask" "F.Paste")
			(net "M_BMC_DDR4_DQ<10>")
		)
		(pad "C7" smd circle
			(at 1.599946 -4.400042)
			(size 0.3683 0.3683)
			(layers "F.Cu" "F.Mask" "F.Paste")
			(net "M_BMC_DDR4_DQ<11>")
		)
		(pad "C8" smd circle
			(at 2.400046 -4.400042)
			(size 0.3683 0.3683)
			(layers "F.Cu" "F.Mask" "F.Paste")
			(net "M_BMC_DDR4_DQ<13>")
		)
		(pad "C9" smd circle
			(at 3.199892 -4.400042)
			(size 0.3683 0.3683)
			(layers "F.Cu" "F.Mask" "F.Paste")
			(net "GND")
		)
		(pad "D1" smd circle
			(at -3.199892 -3.599942)
			(size 0.3683 0.3683)
			(layers "F.Cu" "F.Mask" "F.Paste")
			(net "P1V2_AUX")
		)
		(pad "D2" smd circle
			(at -2.400046 -3.599942)
			(size 0.3683 0.3683)
			(layers "F.Cu" "F.Mask" "F.Paste")
			(net "GND")
		)
		(pad "D3" smd circle
			(at -1.599946 -3.599942)
			(size 0.3683 0.3683)
			(layers "F.Cu" "F.Mask" "F.Paste")
			(net "M_BMC_DDR4_DQ<14>")
		)
		(pad "D7" smd circle
			(at 1.599946 -3.599942)
			(size 0.3683 0.3683)
			(layers "F.Cu" "F.Mask" "F.Paste")
			(net "M_BMC_DDR4_DQ<15>")
		)
		(pad "D8" smd circle
			(at 2.400046 -3.599942)
			(size 0.3683 0.3683)
			(layers "F.Cu" "F.Mask" "F.Paste")
			(net "GND")
		)
		(pad "D9" smd circle
			(at 3.199892 -3.599942)
			(size 0.3683 0.3683)
			(layers "F.Cu" "F.Mask" "F.Paste")
			(net "P1V2_AUX")
		)
		(pad "E1" smd circle
			(at -3.199892 -2.800096)
			(size 0.3683 0.3683)
			(layers "F.Cu" "F.Mask" "F.Paste")
			(net "GND")
		)
		(pad "E2" smd circle
			(at -2.400046 -2.800096)
			(size 0.3683 0.3683)
			(layers "F.Cu" "F.Mask" "F.Paste")
			(net "M_BMC_DDR4_MDM1")
		)
		(pad "E3" smd circle
			(at -1.599946 -2.800096)
			(size 0.3683 0.3683)
			(layers "F.Cu" "F.Mask" "F.Paste")
			(net "GND")
		)
		(pad "E7" smd circle
			(at 1.599946 -2.800096)
			(size 0.3683 0.3683)
			(layers "F.Cu" "F.Mask" "F.Paste")
			(net "M_BMC_DDR4_MDM0")
		)
		(pad "E8" smd circle
			(at 2.400046 -2.800096)
			(size 0.3683 0.3683)
			(layers "F.Cu" "F.Mask" "F.Paste")
			(net "GND")
		)
		(pad "E9" smd circle
			(at 3.199892 -2.800096)
			(size 0.3683 0.3683)
			(layers "F.Cu" "F.Mask" "F.Paste")
			(net "M_BMC_DDR4_ZQU")
		)
		(pad "F1" smd circle
			(at -3.199892 -1.999996)
			(size 0.3683 0.3683)
			(layers "F.Cu" "F.Mask" "F.Paste")
			(net "GND")
		)
		(pad "F2" smd circle
			(at -2.400046 -1.999996)
			(size 0.3683 0.3683)
			(layers "F.Cu" "F.Mask" "F.Paste")
			(net "P1V2_AUX")
		)
		(pad "F3" smd circle
			(at -1.599946 -1.999996)
			(size 0.3683 0.3683)
			(layers "F.Cu" "F.Mask" "F.Paste")
			(net "M_BMC_DDR4_DQS0_N")
		)
		(pad "F7" smd circle
			(at 1.599946 -1.999996)
			(size 0.3683 0.3683)
			(layers "F.Cu" "F.Mask" "F.Paste")
			(net "M_BMC_DDR4_DQ<1>")
		)
		(pad "F8" smd circle
			(at 2.400046 -1.999996)
			(size 0.3683 0.3683)
			(layers "F.Cu" "F.Mask" "F.Paste")
			(net "P1V2_AUX")
		)
		(pad "F9" smd circle
			(at 3.199892 -1.999996)
			(size 0.3683 0.3683)
			(layers "F.Cu" "F.Mask" "F.Paste")
			(net "PD_M_BMC_DDR4_ZQ")
		)
		(pad "G1" smd circle
			(at -3.199892 -1.199896)
			(size 0.3683 0.3683)
			(layers "F.Cu" "F.Mask" "F.Paste")
			(net "P1V2_AUX")
		)
		(pad "G2" smd circle
			(at -2.400046 -1.199896)
			(size 0.3683 0.3683)
			(layers "F.Cu" "F.Mask" "F.Paste")
			(net "M_BMC_DDR4_DQ<0>")
		)
		(pad "G3" smd circle
			(at -1.599946 -1.199896)
			(size 0.3683 0.3683)
			(layers "F.Cu" "F.Mask" "F.Paste")
			(net "M_BMC_DDR4_DQS0_P")
		)
		(pad "G7" smd circle
			(at 1.599946 -1.199896)
			(size 0.3683 0.3683)
			(layers "F.Cu" "F.Mask" "F.Paste")
			(net "P1V2_AUX")
		)
		(pad "G8" smd circle
			(at 2.400046 -1.199896)
			(size 0.3683 0.3683)
			(layers "F.Cu" "F.Mask" "F.Paste")
			(net "GND")
		)
		(pad "G9" smd circle
			(at 3.199892 -1.199896)
			(size 0.3683 0.3683)
			(layers "F.Cu" "F.Mask" "F.Paste")
			(net "P1V2_AUX")
		)
		(pad "H1" smd circle
			(at -3.199892 -0.40005)
			(size 0.3683 0.3683)
			(layers "F.Cu" "F.Mask" "F.Paste")
			(net "GND")
		)
		(pad "H2" smd circle
			(at -2.400046 -0.40005)
			(size 0.3683 0.3683)
			(layers "F.Cu" "F.Mask" "F.Paste")
			(net "M_BMC_DDR4_DQ<4>")
		)
		(pad "H3" smd circle
			(at -1.599946 -0.40005)
			(size 0.3683 0.3683)
			(layers "F.Cu" "F.Mask" "F.Paste")
			(net "M_BMC_DDR4_DQ<2>")
		)
		(pad "H7" smd circle
			(at 1.599946 -0.40005)
			(size 0.3683 0.3683)
			(layers "F.Cu" "F.Mask" "F.Paste")
			(net "M_BMC_DDR4_DQ<3>")
		)
		(pad "H8" smd circle
			(at 2.400046 -0.40005)
			(size 0.3683 0.3683)
			(layers "F.Cu" "F.Mask" "F.Paste")
			(net "M_BMC_DDR4_DQ<5>")
		)
		(pad "H9" smd circle
			(at 3.199892 -0.40005)
			(size 0.3683 0.3683)
			(layers "F.Cu" "F.Mask" "F.Paste")
			(net "GND")
		)
	)
)
